#ISCELL
  mstr_symbols cad_note *
  *
#ISCELL
  mstr_symbols design_note *
  *
#ISCELL
  mstr_symbols intel_corp_bpage *
  *
#ISCELL
  mstr_standard offpage *
  page169_i103
#ISCELL
  mstr_standard offpage *
  page169_i105
#CELL
  mstr_discrete res *
  page169_i106
#ISCELL
  mstr_symbols gnd *
  page169_i107
#CELL
  mstr_discrete cap *
  page169_i108
#ISCELL
  mstr_symbols gnd *
  page169_i109
#CELL
  mstr_discrete res *
  page169_i114
#CELL
  mstr_discrete res *
  page169_i115
#CELL
  mstr_discrete res *
  page169_i116
#ISCELL
  mstr_symbols p5v_stby *
  page169_i119
#ISCELL
  mstr_symbols p1v05_pch_stby *
  page169_i121
#CELL
  mstr_discrete res *
  page169_i126
#ISCELL
  mstr_symbols p3v3_stby *
  page169_i131
#ISCELL
  mstr_symbols p12v_stby *
  page169_i132
#ISCELL
  mstr_standard offpage *
  page169_i138
#CELL
  mstr_discrete cap *
  page169_i139
#CELL
  mstr_discrete res *
  page169_i141
#CELL
  mstr_discrete res *
  page169_i142
#ISCELL
  mstr_symbols gnd *
  page169_i143
#ISCELL
  mstr_symbols p5v *
  page169_i144
#ISCELL
  mstr_standard offpage *
  page169_i145
#CELL
  mstr_discrete cap *
  page169_i146
#CELL
  mstr_discrete res *
  page169_i148
#CELL
  mstr_discrete res *
  page169_i149
#ISCELL
  mstr_symbols gnd *
  page169_i150
#ISCELL
  mstr_symbols p3v3 *
  page169_i151
#ISCELL
  mstr_standard offpage *
  page169_i152
#CELL
  mstr_discrete cap *
  page169_i153
#ISCELL
  mstr_symbols pvnn_pch_stby *
  page169_i154
#CELL
  mstr_discrete ferrite *
  page169_i155
#ISCELL
  mstr_symbols gnd *
  page169_i156
#CELL
  mstr_discrete fet_n_dual *
  page169_i157
#ISCELL
  mstr_symbols gnd *
  page169_i160
#ISCELL
  mstr_standard offpage *
  page169_i161
#CELL
  mstr_discrete fet_n_dual *
  page169_i162
#CELL
  mstr_discrete res *
  page169_i163
#CELL
  mstr_discrete res *
  page169_i164
#ISCELL
  mstr_symbols p3v3_stby *
  page169_i165
#ISCELL
  mstr_symbols p3v3_stby *
  page169_i166
#ISCELL
  mstr_standard offpage *
  page169_i55
#CELL
  mstr_discrete cap *
  page169_i56
#CELL
  mstr_discrete ferrite *
  page169_i57
#ISCELL
  mstr_symbols gnd *
  page169_i58
#ISCELL
  mstr_standard offpage *
  page169_i67
#CELL
  mstr_discrete cap *
  page169_i68
#ISCELL
  mstr_symbols gnd *
  page169_i71
#ISCELL
  mstr_standard offpage *
  page169_i79
#CELL
  mstr_discrete cap *
  page169_i80
#CELL
  mstr_discrete res *
  page169_i82
#CELL
  mstr_discrete res *
  page169_i83
#ISCELL
  mstr_symbols gnd *
  page169_i84
#ISCELL
  mstr_standard offpage *
  page169_i85
#CELL
  mstr_discrete cap *
  page169_i86
#CELL
  mstr_discrete res *
  page169_i88
#ISCELL
  mstr_symbols gnd *
  page169_i90
